(kicad_pcb
	(version 20260206)
	(generator "pcbnew")
	(generator_version "10.0")
	(general
		(thickness 1.6)
		(legacy_teardrops no)
	)
	(paper "A4")
	(title_block
		(title "04192023_DAF0TMB3IC0_F0TG_MB_C_brd_V02_OCP.brd")
		(comment 1 "Grand Teton / footprints 429-435 of 8354")
	)
	(layers
		(0 "F.Cu" signal "TOP")
		(4 "In1.Cu" signal "GND")
		(6 "In2.Cu" signal "IN1")
		(8 "In3.Cu" signal "GND1")
		(10 "In4.Cu" signal "IN2")
		(12 "In5.Cu" signal "GND2")
		(14 "In6.Cu" signal "IN3")
		(16 "In7.Cu" signal "GND3")
		(18 "In8.Cu" signal "VCC")
		(20 "In9.Cu" signal "VCC1")
		(22 "In10.Cu" signal "GND4")
		(24 "In11.Cu" signal "IN4")
		(26 "In12.Cu" signal "GND5")
		(28 "In13.Cu" signal "IN5")
		(30 "In14.Cu" signal "GND6")
		(32 "In15.Cu" signal "IN6")
		(34 "In16.Cu" signal "GND7")
		(2 "B.Cu" signal "BOTTOM")
		(9 "F.Adhes" user "F.Adhesive")
		(11 "B.Adhes" user "B.Adhesive")
		(13 "F.Paste" user "Package Geometry/Pastemask Top")
		(15 "B.Paste" user "Package Geometry/Pastemask Bottom")
		(5 "F.SilkS" user "Ref Des/Silkscreen Top")
		(7 "B.SilkS" user "Ref Des/Silkscreen Bottom")
		(1 "F.Mask" user "Board Geometry/Soldermask Top")
		(3 "B.Mask" user "Board Geometry/Soldermask Bottom")
		(17 "Dwgs.User" user "User.Drawings")
		(19 "Cmts.User" user "User.Comments")
		(21 "Eco1.User" user "User.Eco1")
		(23 "Eco2.User" user "User.Eco2")
		(25 "Edge.Cuts" user "Board Geometry/Outline")
		(27 "Margin" user)
		(31 "F.CrtYd" user "Package Geometry/Place Bound Top")
		(29 "B.CrtYd" user "Package Geometry/Place Bound Bottom")
		(35 "F.Fab" user "Ref Des/Assembly Top")
		(33 "B.Fab" user "Ref Des/Assembly Bottom")
	)
	(footprint ""
		(layer "F.Cu")
		(at 192.913 -96.103948 90)
		(property "Reference" "R391"
			(at 0 0 90)
			(layer "F.SilkS")
			(hide yes)
			(effects
				(font
					(size 1.27 1.27)
				)
			)
		)
		(property "Value" ""
			(at 0 0 90)
			(layer "F.Fab")
			(effects
				(font
					(size 1.27 1.27)
				)
			)
		)
		(duplicate_pad_numbers_are_jumpers no)
		(fp_line
			(start 0.7874 -0.4064)
			(end 0.7874 0.4064)
			(stroke
				(width 0.1524)
				(type default)
			)
			(layer "F.SilkS")
		)
		(fp_line
			(start -0.7874 -0.4064)
			(end 0.7874 -0.4064)
			(stroke
				(width 0.1524)
				(type default)
			)
			(layer "F.SilkS")
		)
		(fp_line
			(start 0.7874 0.4064)
			(end -0.7874 0.4064)
			(stroke
				(width 0.1524)
				(type default)
			)
			(layer "F.SilkS")
		)
		(fp_line
			(start -0.7874 0.4064)
			(end -0.7874 -0.4064)
			(stroke
				(width 0.1524)
				(type default)
			)
			(layer "F.SilkS")
		)
		(fp_line
			(start -0.12065 -0.305054)
			(end -0.12065 -0.2794)
			(stroke
				(width 0.1)
				(type default)
			)
			(layer "F.Fab")
		)
		(fp_line
			(start -0.67945 -0.305054)
			(end -0.12065 -0.305054)
			(stroke
				(width 0.1)
				(type default)
			)
			(layer "F.Fab")
		)
		(fp_line
			(start 0.67945 -0.3048)
			(end 0.67945 0.3048)
			(stroke
				(width 0.1)
				(type default)
			)
			(layer "F.Fab")
		)
		(fp_line
			(start 0.12065 -0.3048)
			(end 0.67945 -0.3048)
			(stroke
				(width 0.1)
				(type default)
			)
			(layer "F.Fab")
		)
		(fp_line
			(start 0.12065 -0.2794)
			(end 0.12065 -0.3048)
			(stroke
				(width 0.1)
				(type default)
			)
			(layer "F.Fab")
		)
		(fp_line
			(start -0.12065 -0.2794)
			(end 0.12065 -0.2794)
			(stroke
				(width 0.1)
				(type default)
			)
			(layer "F.Fab")
		)
		(fp_line
			(start 0.120396 0.2794)
			(end -0.12065 0.2794)
			(stroke
				(width 0.1)
				(type default)
			)
			(layer "F.Fab")
		)
		(fp_line
			(start -0.12065 0.2794)
			(end -0.12065 0.3048)
			(stroke
				(width 0.1)
				(type default)
			)
			(layer "F.Fab")
		)
		(fp_line
			(start 0.67945 0.3048)
			(end 0.120396 0.3048)
			(stroke
				(width 0.1)
				(type default)
			)
			(layer "F.Fab")
		)
		(fp_line
			(start 0.120396 0.3048)
			(end 0.120396 0.2794)
			(stroke
				(width 0.1)
				(type default)
			)
			(layer "F.Fab")
		)
		(fp_line
			(start -0.12065 0.3048)
			(end -0.67945 0.3048)
			(stroke
				(width 0.1)
				(type default)
			)
			(layer "F.Fab")
		)
		(fp_line
			(start -0.67945 0.3048)
			(end -0.67945 -0.305054)
			(stroke
				(width 0.1)
				(type default)
			)
			(layer "F.Fab")
		)
		(pad "1" smd circle
			(at -0.40005 0 90)
			(size 0 0)
			(layers "F.Cu" "F.Mask" "F.Paste")
			(net "P3V3_AUX")
		)
		(pad "2" smd circle
			(at 0.40005 0 90)
			(size 0 0)
			(layers "F.Cu" "F.Mask" "F.Paste")
			(net "CPU0_SP5R3")
		)
	)
	(footprint ""
		(layer "F.Cu")
		(at 461.592168 -109.646212)
		(property "Reference" "R576"
			(at 0 0 0)
			(layer "F.SilkS")
			(hide yes)
			(effects
				(font
					(size 1.27 1.27)
				)
			)
		)
		(property "Value" ""
			(at 0 0 0)
			(layer "F.Fab")
			(effects
				(font
					(size 1.27 1.27)
				)
			)
		)
		(duplicate_pad_numbers_are_jumpers no)
		(fp_line
			(start -0.7874 -0.4064)
			(end 0.7874 -0.4064)
			(stroke
				(width 0.1524)
				(type default)
			)
			(layer "F.SilkS")
		)
		(fp_line
			(start -0.7874 0.4064)
			(end -0.7874 -0.4064)
			(stroke
				(width 0.1524)
				(type default)
			)
			(layer "F.SilkS")
		)
		(fp_line
			(start 0.7874 -0.4064)
			(end 0.7874 0.4064)
			(stroke
				(width 0.1524)
				(type default)
			)
			(layer "F.SilkS")
		)
		(fp_line
			(start 0.7874 0.4064)
			(end -0.7874 0.4064)
			(stroke
				(width 0.1524)
				(type default)
			)
			(layer "F.SilkS")
		)
		(fp_line
			(start -0.67945 -0.305054)
			(end -0.12065 -0.305054)
			(stroke
				(width 0.1)
				(type default)
			)
			(layer "F.Fab")
		)
		(fp_line
			(start -0.67945 0.3048)
			(end -0.67945 -0.305054)
			(stroke
				(width 0.1)
				(type default)
			)
			(layer "F.Fab")
		)
		(fp_line
			(start -0.12065 -0.305054)
			(end -0.12065 -0.2794)
			(stroke
				(width 0.1)
				(type default)
			)
			(layer "F.Fab")
		)
		(fp_line
			(start -0.12065 -0.2794)
			(end 0.12065 -0.2794)
			(stroke
				(width 0.1)
				(type default)
			)
			(layer "F.Fab")
		)
		(fp_line
			(start -0.12065 0.2794)
			(end -0.12065 0.3048)
			(stroke
				(width 0.1)
				(type default)
			)
			(layer "F.Fab")
		)
		(fp_line
			(start -0.12065 0.3048)
			(end -0.67945 0.3048)
			(stroke
				(width 0.1)
				(type default)
			)
			(layer "F.Fab")
		)
		(fp_line
			(start 0.120396 0.2794)
			(end -0.12065 0.2794)
			(stroke
				(width 0.1)
				(type default)
			)
			(layer "F.Fab")
		)
		(fp_line
			(start 0.120396 0.3048)
			(end 0.120396 0.2794)
			(stroke
				(width 0.1)
				(type default)
			)
			(layer "F.Fab")
		)
		(fp_line
			(start 0.12065 -0.3048)
			(end 0.67945 -0.3048)
			(stroke
				(width 0.1)
				(type default)
			)
			(layer "F.Fab")
		)
		(fp_line
			(start 0.12065 -0.2794)
			(end 0.12065 -0.3048)
			(stroke
				(width 0.1)
				(type default)
			)
			(layer "F.Fab")
		)
		(fp_line
			(start 0.67945 -0.3048)
			(end 0.67945 0.3048)
			(stroke
				(width 0.1)
				(type default)
			)
			(layer "F.Fab")
		)
		(fp_line
			(start 0.67945 0.3048)
			(end 0.120396 0.3048)
			(stroke
				(width 0.1)
				(type default)
			)
			(layer "F.Fab")
		)
		(pad "1" smd circle
			(at -0.40005 0)
			(size 0 0)
			(layers "F.Cu" "F.Mask" "F.Paste")
			(net "HP_LVC3_OCP_V3_1_PRSNT2_N_R")
		)
		(pad "2" smd circle
			(at 0.40005 0)
			(size 0 0)
			(layers "F.Cu" "F.Mask" "F.Paste")
			(net "HP_LVC3_OCP_SFF_PRSNT2_N")
		)
	)
	(footprint ""
		(layer "F.Cu")
		(at 83.428332 -331.97419 180)
		(property "Reference" "PC201"
			(at 0 0 180)
			(layer "F.SilkS")
			(hide yes)
			(effects
				(font
					(size 1.27 1.27)
				)
			)
		)
		(property "Value" ""
			(at 0 0 180)
			(layer "F.Fab")
			(effects
				(font
					(size 1.27 1.27)
				)
			)
		)
		(duplicate_pad_numbers_are_jumpers no)
		(fp_line
			(start 0.7874 0.4064)
			(end -0.7874 0.4064)
			(stroke
				(width 0.1524)
				(type default)
			)
			(layer "F.SilkS")
		)
		(fp_line
			(start 0.7874 -0.4064)
			(end 0.7874 0.4064)
			(stroke
				(width 0.1524)
				(type default)
			)
			(layer "F.SilkS")
		)
		(fp_line
			(start -0.7874 0.4064)
			(end -0.7874 -0.4064)
			(stroke
				(width 0.1524)
				(type default)
			)
			(layer "F.SilkS")
		)
		(fp_line
			(start -0.7874 -0.4064)
			(end 0.7874 -0.4064)
			(stroke
				(width 0.1524)
				(type default)
			)
			(layer "F.SilkS")
		)
		(fp_line
			(start 0.67945 0.3048)
			(end 0.120396 0.3048)
			(stroke
				(width 0.1)
				(type default)
			)
			(layer "F.Fab")
		)
		(fp_line
			(start 0.67945 -0.3048)
			(end 0.67945 0.3048)
			(stroke
				(width 0.1)
				(type default)
			)
			(layer "F.Fab")
		)
		(fp_line
			(start 0.12065 -0.2794)
			(end 0.12065 -0.3048)
			(stroke
				(width 0.1)
				(type default)
			)
			(layer "F.Fab")
		)
		(fp_line
			(start 0.12065 -0.3048)
			(end 0.67945 -0.3048)
			(stroke
				(width 0.1)
				(type default)
			)
			(layer "F.Fab")
		)
		(fp_line
			(start 0.120396 0.3048)
			(end 0.120396 0.2794)
			(stroke
				(width 0.1)
				(type default)
			)
			(layer "F.Fab")
		)
		(fp_line
			(start 0.120396 0.2794)
			(end -0.12065 0.2794)
			(stroke
				(width 0.1)
				(type default)
			)
			(layer "F.Fab")
		)
		(fp_line
			(start -0.12065 0.3048)
			(end -0.67945 0.3048)
			(stroke
				(width 0.1)
				(type default)
			)
			(layer "F.Fab")
		)
		(fp_line
			(start -0.12065 0.2794)
			(end -0.12065 0.3048)
			(stroke
				(width 0.1)
				(type default)
			)
			(layer "F.Fab")
		)
		(fp_line
			(start -0.12065 -0.2794)
			(end 0.12065 -0.2794)
			(stroke
				(width 0.1)
				(type default)
			)
			(layer "F.Fab")
		)
		(fp_line
			(start -0.12065 -0.305054)
			(end -0.12065 -0.2794)
			(stroke
				(width 0.1)
				(type default)
			)
			(layer "F.Fab")
		)
		(fp_line
			(start -0.67945 0.3048)
			(end -0.67945 -0.305054)
			(stroke
				(width 0.1)
				(type default)
			)
			(layer "F.Fab")
		)
		(fp_line
			(start -0.67945 -0.305054)
			(end -0.12065 -0.305054)
			(stroke
				(width 0.1)
				(type default)
			)
			(layer "F.Fab")
		)
		(pad "1" smd circle
			(at -0.40005 0 180)
			(size 0 0)
			(layers "F.Cu" "F.Mask" "F.Paste")
			(net "SW_PVDDCR_CPU1_P1_SW1")
		)
		(pad "2" smd circle
			(at 0.40005 0 180)
			(size 0 0)
			(layers "F.Cu" "F.Mask" "F.Paste")
			(net "SW_PVDDCR_CPU1_P1_SW1_RC")
		)
	)
	(footprint ""
		(layer "F.Cu")
		(at 22.479 -359.918 180)
		(property "Reference" "C310"
			(at 0 0 180)
			(layer "F.SilkS")
			(hide yes)
			(effects
				(font
					(size 1.27 1.27)
				)
			)
		)
		(property "Value" ""
			(at 0 0 180)
			(layer "F.Fab")
			(effects
				(font
					(size 1.27 1.27)
				)
			)
		)
		(duplicate_pad_numbers_are_jumpers no)
		(fp_line
			(start 0.7874 0.4064)
			(end -0.7874 0.4064)
			(stroke
				(width 0.1524)
				(type default)
			)
			(layer "F.SilkS")
		)
		(fp_line
			(start 0.7874 -0.4064)
			(end 0.7874 0.4064)
			(stroke
				(width 0.1524)
				(type default)
			)
			(layer "F.SilkS")
		)
		(fp_line
			(start -0.7874 0.4064)
			(end -0.7874 -0.4064)
			(stroke
				(width 0.1524)
				(type default)
			)
			(layer "F.SilkS")
		)
		(fp_line
			(start -0.7874 -0.4064)
			(end 0.7874 -0.4064)
			(stroke
				(width 0.1524)
				(type default)
			)
			(layer "F.SilkS")
		)
		(fp_line
			(start 0.67945 0.3048)
			(end 0.120396 0.3048)
			(stroke
				(width 0.1)
				(type default)
			)
			(layer "F.Fab")
		)
		(fp_line
			(start 0.67945 -0.3048)
			(end 0.67945 0.3048)
			(stroke
				(width 0.1)
				(type default)
			)
			(layer "F.Fab")
		)
		(fp_line
			(start 0.12065 -0.2794)
			(end 0.12065 -0.3048)
			(stroke
				(width 0.1)
				(type default)
			)
			(layer "F.Fab")
		)
		(fp_line
			(start 0.12065 -0.3048)
			(end 0.67945 -0.3048)
			(stroke
				(width 0.1)
				(type default)
			)
			(layer "F.Fab")
		)
		(fp_line
			(start 0.120396 0.3048)
			(end 0.120396 0.2794)
			(stroke
				(width 0.1)
				(type default)
			)
			(layer "F.Fab")
		)
		(fp_line
			(start 0.120396 0.2794)
			(end -0.12065 0.2794)
			(stroke
				(width 0.1)
				(type default)
			)
			(layer "F.Fab")
		)
		(fp_line
			(start -0.12065 0.3048)
			(end -0.67945 0.3048)
			(stroke
				(width 0.1)
				(type default)
			)
			(layer "F.Fab")
		)
		(fp_line
			(start -0.12065 0.2794)
			(end -0.12065 0.3048)
			(stroke
				(width 0.1)
				(type default)
			)
			(layer "F.Fab")
		)
		(fp_line
			(start -0.12065 -0.2794)
			(end 0.12065 -0.2794)
			(stroke
				(width 0.1)
				(type default)
			)
			(layer "F.Fab")
		)
		(fp_line
			(start -0.12065 -0.305054)
			(end -0.12065 -0.2794)
			(stroke
				(width 0.1)
				(type default)
			)
			(layer "F.Fab")
		)
		(fp_line
			(start -0.67945 0.3048)
			(end -0.67945 -0.305054)
			(stroke
				(width 0.1)
				(type default)
			)
			(layer "F.Fab")
		)
		(fp_line
			(start -0.67945 -0.305054)
			(end -0.12065 -0.305054)
			(stroke
				(width 0.1)
				(type default)
			)
			(layer "F.Fab")
		)
		(pad "1" smd circle
			(at -0.40005 0 180)
			(size 0 0)
			(layers "F.Cu" "F.Mask" "F.Paste")
			(net "SVID_PVDDCR_CPU1_P1_SVC_R")
		)
		(pad "2" smd circle
			(at 0.40005 0 180)
			(size 0 0)
			(layers "F.Cu" "F.Mask" "F.Paste")
			(net "GND")
		)
	)
	(footprint ""
		(layer "F.Cu")
		(at 236.7661 -400.871182)
		(property "Reference" "PR3994"
			(at 0 0 0)
			(layer "F.SilkS")
			(hide yes)
			(effects
				(font
					(size 1.27 1.27)
				)
			)
		)
		(property "Value" ""
			(at 0 0 0)
			(layer "F.Fab")
			(effects
				(font
					(size 1.27 1.27)
				)
			)
		)
		(duplicate_pad_numbers_are_jumpers no)
		(fp_line
			(start -0.7874 -0.4064)
			(end 0.7874 -0.4064)
			(stroke
				(width 0.1524)
				(type default)
			)
			(layer "F.SilkS")
		)
		(fp_line
			(start -0.7874 0.4064)
			(end -0.7874 -0.4064)
			(stroke
				(width 0.1524)
				(type default)
			)
			(layer "F.SilkS")
		)
		(fp_line
			(start 0.7874 -0.4064)
			(end 0.7874 0.4064)
			(stroke
				(width 0.1524)
				(type default)
			)
			(layer "F.SilkS")
		)
		(fp_line
			(start 0.7874 0.4064)
			(end -0.7874 0.4064)
			(stroke
				(width 0.1524)
				(type default)
			)
			(layer "F.SilkS")
		)
		(fp_line
			(start -0.67945 -0.305054)
			(end -0.12065 -0.305054)
			(stroke
				(width 0.1)
				(type default)
			)
			(layer "F.Fab")
		)
		(fp_line
			(start -0.67945 0.3048)
			(end -0.67945 -0.305054)
			(stroke
				(width 0.1)
				(type default)
			)
			(layer "F.Fab")
		)
		(fp_line
			(start -0.12065 -0.305054)
			(end -0.12065 -0.2794)
			(stroke
				(width 0.1)
				(type default)
			)
			(layer "F.Fab")
		)
		(fp_line
			(start -0.12065 -0.2794)
			(end 0.12065 -0.2794)
			(stroke
				(width 0.1)
				(type default)
			)
			(layer "F.Fab")
		)
		(fp_line
			(start -0.12065 0.2794)
			(end -0.12065 0.3048)
			(stroke
				(width 0.1)
				(type default)
			)
			(layer "F.Fab")
		)
		(fp_line
			(start -0.12065 0.3048)
			(end -0.67945 0.3048)
			(stroke
				(width 0.1)
				(type default)
			)
			(layer "F.Fab")
		)
		(fp_line
			(start 0.120396 0.2794)
			(end -0.12065 0.2794)
			(stroke
				(width 0.1)
				(type default)
			)
			(layer "F.Fab")
		)
		(fp_line
			(start 0.120396 0.3048)
			(end 0.120396 0.2794)
			(stroke
				(width 0.1)
				(type default)
			)
			(layer "F.Fab")
		)
		(fp_line
			(start 0.12065 -0.3048)
			(end 0.67945 -0.3048)
			(stroke
				(width 0.1)
				(type default)
			)
			(layer "F.Fab")
		)
		(fp_line
			(start 0.12065 -0.2794)
			(end 0.12065 -0.3048)
			(stroke
				(width 0.1)
				(type default)
			)
			(layer "F.Fab")
		)
		(fp_line
			(start 0.67945 -0.3048)
			(end 0.67945 0.3048)
			(stroke
				(width 0.1)
				(type default)
			)
			(layer "F.Fab")
		)
		(fp_line
			(start 0.67945 0.3048)
			(end 0.120396 0.3048)
			(stroke
				(width 0.1)
				(type default)
			)
			(layer "F.Fab")
		)
		(pad "1" smd circle
			(at -0.40005 0)
			(size 0 0)
			(layers "F.Cu" "F.Mask" "F.Paste")
			(net "HSC_D_OC_4")
		)
		(pad "2" smd circle
			(at 0.40005 0)
			(size 0 0)
			(layers "F.Cu" "F.Mask" "F.Paste")
			(net "HSC_D_OC_R")
		)
	)
	(footprint ""
		(layer "F.Cu")
		(at 55.816754 -375.49963 -90)
		(property "Reference" "C822"
			(at 0 0 270)
			(layer "F.SilkS")
			(hide yes)
			(effects
				(font
					(size 1.27 1.27)
				)
			)
		)
		(property "Value" ""
			(at 0 0 270)
			(layer "F.Fab")
			(effects
				(font
					(size 1.27 1.27)
				)
			)
		)
		(duplicate_pad_numbers_are_jumpers no)
		(fp_line
			(start -0.299974 0.150114)
			(end -0.299974 -0.150114)
			(stroke
				(width 0.1)
				(type default)
			)
			(layer "F.Fab")
		)
		(fp_line
			(start 0.299974 0.150114)
			(end -0.299974 0.150114)
			(stroke
				(width 0.1)
				(type default)
			)
			(layer "F.Fab")
		)
		(fp_line
			(start -0.299974 -0.150114)
			(end 0.299974 -0.150114)
			(stroke
				(width 0.1)
				(type default)
			)
			(layer "F.Fab")
		)
		(fp_line
			(start 0.299974 -0.150114)
			(end 0.299974 0.150114)
			(stroke
				(width 0.1)
				(type default)
			)
			(layer "F.Fab")
		)
		(pad "1" smd rect
			(at -0.2667 0 270)
			(size 0.3048 0.381)
			(layers "F.Cu" "F.Mask" "F.Paste")
			(net "P5E_CPU1_P0_TX_C_DN<7>")
		)
		(pad "2" smd rect
			(at 0.2667 0 270)
			(size 0.3048 0.381)
			(layers "F.Cu" "F.Mask" "F.Paste")
			(net "P5E_CPU1_P0_TX_DN<7>")
		)
	)
	(footprint ""
		(layer "F.Cu")
		(at 36.319968 -134.873238 180)
		(property "Reference" "R3322"
			(at 0 0 180)
			(layer "F.SilkS")
			(hide yes)
			(effects
				(font
					(size 1.27 1.27)
				)
			)
		)
		(property "Value" ""
			(at 0 0 180)
			(layer "F.Fab")
			(effects
				(font
					(size 1.27 1.27)
				)
			)
		)
		(duplicate_pad_numbers_are_jumpers no)
		(fp_line
			(start 0.7874 0.4064)
			(end -0.7874 0.4064)
			(stroke
				(width 0.1524)
				(type default)
			)
			(layer "F.SilkS")
		)
		(fp_line
			(start 0.7874 -0.4064)
			(end 0.7874 0.4064)
			(stroke
				(width 0.1524)
				(type default)
			)
			(layer "F.SilkS")
		)
		(fp_line
			(start -0.7874 0.4064)
			(end -0.7874 -0.4064)
			(stroke
				(width 0.1524)
				(type default)
			)
			(layer "F.SilkS")
		)
		(fp_line
			(start -0.7874 -0.4064)
			(end 0.7874 -0.4064)
			(stroke
				(width 0.1524)
				(type default)
			)
			(layer "F.SilkS")
		)
		(fp_line
			(start 0.67945 0.3048)
			(end 0.120396 0.3048)
			(stroke
				(width 0.1)
				(type default)
			)
			(layer "F.Fab")
		)
		(fp_line
			(start 0.67945 -0.3048)
			(end 0.67945 0.3048)
			(stroke
				(width 0.1)
				(type default)
			)
			(layer "F.Fab")
		)
		(fp_line
			(start 0.12065 -0.2794)
			(end 0.12065 -0.3048)
			(stroke
				(width 0.1)
				(type default)
			)
			(layer "F.Fab")
		)
		(fp_line
			(start 0.12065 -0.3048)
			(end 0.67945 -0.3048)
			(stroke
				(width 0.1)
				(type default)
			)
			(layer "F.Fab")
		)
		(fp_line
			(start 0.120396 0.3048)
			(end 0.120396 0.2794)
			(stroke
				(width 0.1)
				(type default)
			)
			(layer "F.Fab")
		)
		(fp_line
			(start 0.120396 0.2794)
			(end -0.12065 0.2794)
			(stroke
				(width 0.1)
				(type default)
			)
			(layer "F.Fab")
		)
		(fp_line
			(start -0.12065 0.3048)
			(end -0.67945 0.3048)
			(stroke
				(width 0.1)
				(type default)
			)
			(layer "F.Fab")
		)
		(fp_line
			(start -0.12065 0.2794)
			(end -0.12065 0.3048)
			(stroke
				(width 0.1)
				(type default)
			)
			(layer "F.Fab")
		)
		(fp_line
			(start -0.12065 -0.2794)
			(end 0.12065 -0.2794)
			(stroke
				(width 0.1)
				(type default)
			)
			(layer "F.Fab")
		)
		(fp_line
			(start -0.12065 -0.305054)
			(end -0.12065 -0.2794)
			(stroke
				(width 0.1)
				(type default)
			)
			(layer "F.Fab")
		)
		(fp_line
			(start -0.67945 0.3048)
			(end -0.67945 -0.305054)
			(stroke
				(width 0.1)
				(type default)
			)
			(layer "F.Fab")
		)
		(fp_line
			(start -0.67945 -0.305054)
			(end -0.12065 -0.305054)
			(stroke
				(width 0.1)
				(type default)
			)
			(layer "F.Fab")
		)
		(pad "1" smd circle
			(at -0.40005 0 180)
			(size 0 0)
			(layers "F.Cu" "F.Mask" "F.Paste")
			(net "P3V3_AUX")
		)
		(pad "2" smd circle
			(at 0.40005 0 180)
			(size 0 0)
			(layers "F.Cu" "F.Mask" "F.Paste")
			(net "CLK_GEN2_GPU_FPGA_OE_R2_N")
		)
	)
)
